# T6G (Grand Teton) — schematic netlist excerpt (pin names and nets, part order shuffled) for the footprints in the layout excerpt that follows; sources: Cadence DE-HDL packaged netlist, KiCad conversion of 04192023_DAF0TMB3IC0_F0TG_MB_C_brd_V02_OCP.brd

R769  Q_RES  84.5K 1% CHIP  pkg 0402LF  page 97 : A = PD_CHL_CPU0_DIMM_SAA ; B = GND
C6605  Q_CAP_DIFFBUS  DIFF BUS_0.22UF 6.3V 20% X6S  pkg C0201  page 308 : \1\ = P5E_CPU0_P3_TX_BUF_C_DP<4> ; \2\ = P5E_CPU0_P3_TX_BUF_DP<4>
C774  Q_CAP  0.1UF 10V 10% X7S  pkg C0201  page 301 : A = P1V8_CPU0_RT2_1A ; B = GND
PC8014  Q_CAP  22UF 16V 20% X6S  pkg C0805  page 190 : A = SW_P3V3_AUX_FLT ; B = GND

(kicad_pcb
	(version 20260206)
	(generator "pcbnew")
	(generator_version "10.0")
	(general
		(thickness 1.6)
		(legacy_teardrops no)
	)
	(paper "A4")
	(title_block
		(title "04192023_DAF0TMB3IC0_F0TG_MB_C_brd_V02_OCP.brd")
		(comment 1 "Grand Teton / footprints 8304-8307 of 8354")
	)
	(layers
		(0 "F.Cu" signal "TOP")
		(4 "In1.Cu" signal "GND")
		(6 "In2.Cu" signal "IN1")
		(8 "In3.Cu" signal "GND1")
		(10 "In4.Cu" signal "IN2")
		(12 "In5.Cu" signal "GND2")
		(14 "In6.Cu" signal "IN3")
		(16 "In7.Cu" signal "GND3")
		(18 "In8.Cu" signal "VCC")
		(20 "In9.Cu" signal "VCC1")
		(22 "In10.Cu" signal "GND4")
		(24 "In11.Cu" signal "IN4")
		(26 "In12.Cu" signal "GND5")
		(28 "In13.Cu" signal "IN5")
		(30 "In14.Cu" signal "GND6")
		(32 "In15.Cu" signal "IN6")
		(34 "In16.Cu" signal "GND7")
		(2 "B.Cu" signal "BOTTOM")
		(9 "F.Adhes" user "F.Adhesive")
		(11 "B.Adhes" user "B.Adhesive")
		(13 "F.Paste" user "Package Geometry/Pastemask Top")
		(15 "B.Paste" user "Package Geometry/Pastemask Bottom")
		(5 "F.SilkS" user "Ref Des/Silkscreen Top")
		(7 "B.SilkS" user "Ref Des/Silkscreen Bottom")
		(1 "F.Mask" user "Board Geometry/Soldermask Top")
		(3 "B.Mask" user "Board Geometry/Soldermask Bottom")
		(17 "Dwgs.User" user "User.Drawings")
		(19 "Cmts.User" user "User.Comments")
		(21 "Eco1.User" user "User.Eco1")
		(23 "Eco2.User" user "User.Eco2")
		(25 "Edge.Cuts" user "Board Geometry/Outline")
		(27 "Margin" user)
		(31 "F.CrtYd" user "Package Geometry/Place Bound Top")
		(29 "B.CrtYd" user "Package Geometry/Place Bound Bottom")
		(35 "F.Fab" user "Ref Des/Assembly Top")
		(33 "B.Fab" user "Ref Des/Assembly Bottom")
	)
	(footprint ""
		(layer "B.Cu")
		(at 385.567682 -416.899344 90)
		(property "Reference" "C6605"
			(at 0 0 90)
			(layer "B.SilkS")
			(hide yes)
			(effects
				(font
					(size 1.27 1.27)
				)
				(justify mirror)
			)
		)
		(property "Value" ""
			(at 0 0 90)
			(layer "B.Fab")
			(effects
				(font
					(size 1.27 1.27)
				)
				(justify mirror)
			)
		)
		(duplicate_pad_numbers_are_jumpers no)
		(fp_line
			(start 0.299974 -0.150114)
			(end -0.299974 -0.150114)
			(stroke
				(width 0.1)
				(type default)
			)
			(layer "B.Fab")
		)
		(fp_line
			(start -0.299974 -0.150114)
			(end -0.299974 0.150114)
			(stroke
				(width 0.1)
				(type default)
			)
			(layer "B.Fab")
		)
		(fp_line
			(start 0.299974 0.150114)
			(end 0.299974 -0.150114)
			(stroke
				(width 0.1)
				(type default)
			)
			(layer "B.Fab")
		)
		(fp_line
			(start -0.299974 0.150114)
			(end 0.299974 0.150114)
			(stroke
				(width 0.1)
				(type default)
			)
			(layer "B.Fab")
		)
		(pad "1" smd rect
			(at 0.2667 0 270)
			(size 0.3048 0.381)
			(layers "B.Cu" "B.Mask" "B.Paste")
			(net "P5E_CPU0_P3_TX_BUF_C_DP<4>")
		)
		(pad "2" smd rect
			(at -0.2667 0 270)
			(size 0.3048 0.381)
			(layers "B.Cu" "B.Mask" "B.Paste")
			(net "P5E_CPU0_P3_TX_BUF_DP<4>")
		)
	)
	(footprint ""
		(layer "B.Cu")
		(at 450.84365 -194.88531 180)
		(property "Reference" "R769"
			(at 0 0 0)
			(layer "B.SilkS")
			(hide yes)
			(effects
				(font
					(size 1.27 1.27)
				)
				(justify mirror)
			)
		)
		(property "Value" ""
			(at 0 0 0)
			(layer "B.Fab")
			(effects
				(font
					(size 1.27 1.27)
				)
				(justify mirror)
			)
		)
		(duplicate_pad_numbers_are_jumpers no)
		(fp_line
			(start 0.7874 0.4064)
			(end 0.7874 -0.4064)
			(stroke
				(width 0.1524)
				(type default)
			)
			(layer "B.SilkS")
		)
		(fp_line
			(start 0.7874 -0.4064)
			(end -0.7874 -0.4064)
			(stroke
				(width 0.1524)
				(type default)
			)
			(layer "B.SilkS")
		)
		(fp_line
			(start -0.7874 0.4064)
			(end 0.7874 0.4064)
			(stroke
				(width 0.1524)
				(type default)
			)
			(layer "B.SilkS")
		)
		(fp_line
			(start -0.7874 -0.4064)
			(end -0.7874 0.4064)
			(stroke
				(width 0.1524)
				(type default)
			)
			(layer "B.SilkS")
		)
		(fp_line
			(start 0.67945 0.3048)
			(end 0.67945 -0.305054)
			(stroke
				(width 0.1)
				(type default)
			)
			(layer "B.Fab")
		)
		(fp_line
			(start 0.67945 -0.305054)
			(end 0.12065 -0.305054)
			(stroke
				(width 0.1)
				(type default)
			)
			(layer "B.Fab")
		)
		(fp_line
			(start 0.12065 0.3048)
			(end 0.67945 0.3048)
			(stroke
				(width 0.1)
				(type default)
			)
			(layer "B.Fab")
		)
		(fp_line
			(start 0.12065 0.2794)
			(end 0.12065 0.3048)
			(stroke
				(width 0.1)
				(type default)
			)
			(layer "B.Fab")
		)
		(fp_line
			(start 0.12065 -0.2794)
			(end -0.12065 -0.2794)
			(stroke
				(width 0.1)
				(type default)
			)
			(layer "B.Fab")
		)
		(fp_line
			(start 0.12065 -0.305054)
			(end 0.12065 -0.2794)
			(stroke
				(width 0.1)
				(type default)
			)
			(layer "B.Fab")
		)
		(fp_line
			(start -0.120396 0.3048)
			(end -0.120396 0.2794)
			(stroke
				(width 0.1)
				(type default)
			)
			(layer "B.Fab")
		)
		(fp_line
			(start -0.120396 0.2794)
			(end 0.12065 0.2794)
			(stroke
				(width 0.1)
				(type default)
			)
			(layer "B.Fab")
		)
		(fp_line
			(start -0.12065 -0.2794)
			(end -0.12065 -0.3048)
			(stroke
				(width 0.1)
				(type default)
			)
			(layer "B.Fab")
		)
		(fp_line
			(start -0.12065 -0.3048)
			(end -0.67945 -0.3048)
			(stroke
				(width 0.1)
				(type default)
			)
			(layer "B.Fab")
		)
		(fp_line
			(start -0.67945 0.3048)
			(end -0.120396 0.3048)
			(stroke
				(width 0.1)
				(type default)
			)
			(layer "B.Fab")
		)
		(fp_line
			(start -0.67945 -0.3048)
			(end -0.67945 0.3048)
			(stroke
				(width 0.1)
				(type default)
			)
			(layer "B.Fab")
		)
		(pad "1" smd circle
			(at 0.40005 0)
			(size 0 0)
			(layers "B.Cu" "B.Mask" "B.Paste")
			(net "PD_CHL_CPU0_DIMM_SAA")
		)
		(pad "2" smd circle
			(at -0.40005 0)
			(size 0 0)
			(layers "B.Cu" "B.Mask" "B.Paste")
			(net "GND")
		)
	)
	(footprint ""
		(layer "B.Cu")
		(at 446.258442 -53.188108 -90)
		(property "Reference" "PC8014"
			(at 0 0 90)
			(layer "B.SilkS")
			(hide yes)
			(effects
				(font
					(size 1.27 1.27)
				)
				(justify mirror)
			)
		)
		(property "Value" ""
			(at 0 0 90)
			(layer "B.Fab")
			(effects
				(font
					(size 1.27 1.27)
				)
				(justify mirror)
			)
		)
		(duplicate_pad_numbers_are_jumpers no)
		(fp_line
			(start -1.524 0.762)
			(end 1.524 0.762)
			(stroke
				(width 0.1524)
				(type default)
			)
			(layer "B.SilkS")
		)
		(fp_line
			(start 1.524 0.762)
			(end 1.524 -0.762)
			(stroke
				(width 0.1524)
				(type default)
			)
			(layer "B.SilkS")
		)
		(fp_line
			(start -1.524 -0.762)
			(end -1.524 0.762)
			(stroke
				(width 0.1524)
				(type default)
			)
			(layer "B.SilkS")
		)
		(fp_line
			(start 1.524 -0.762)
			(end -1.524 -0.762)
			(stroke
				(width 0.1524)
				(type default)
			)
			(layer "B.SilkS")
		)
		(fp_line
			(start -1.1049 0.724916)
			(end -1.1049 -0.724916)
			(stroke
				(width 0.1)
				(type default)
			)
			(layer "B.Fab")
		)
		(fp_line
			(start 1.1049 0.724916)
			(end -1.1049 0.724916)
			(stroke
				(width 0.1)
				(type default)
			)
			(layer "B.Fab")
		)
		(fp_line
			(start -1.1049 -0.724916)
			(end 1.1049 -0.724916)
			(stroke
				(width 0.1)
				(type default)
			)
			(layer "B.Fab")
		)
		(fp_line
			(start 1.1049 -0.724916)
			(end 1.1049 0.724916)
			(stroke
				(width 0.1)
				(type default)
			)
			(layer "B.Fab")
		)
		(pad "1" smd rect
			(at 0.889 0 270)
			(size 1.016 1.27)
			(layers "B.Cu" "B.Mask" "B.Paste")
			(net "SW_P3V3_AUX_FLT")
		)
		(pad "2" smd rect
			(at -0.889 0 270)
			(size 1.016 1.27)
			(layers "B.Cu" "B.Mask" "B.Paste")
			(net "GND")
		)
	)
	(footprint ""
		(layer "B.Cu")
		(at 411.40634 -395.148562 90)
		(property "Reference" "C774"
			(at 0 0 90)
			(layer "B.SilkS")
			(hide yes)
			(effects
				(font
					(size 1.27 1.27)
				)
				(justify mirror)
			)
		)
		(property "Value" ""
			(at 0 0 90)
			(layer "B.Fab")
			(effects
				(font
					(size 1.27 1.27)
				)
				(justify mirror)
			)
		)
		(duplicate_pad_numbers_are_jumpers no)
		(fp_line
			(start 0.299974 -0.150114)
			(end -0.299974 -0.150114)
			(stroke
				(width 0.1)
				(type default)
			)
			(layer "B.Fab")
		)
		(fp_line
			(start -0.299974 -0.150114)
			(end -0.299974 0.150114)
			(stroke
				(width 0.1)
				(type default)
			)
			(layer "B.Fab")
		)
		(fp_line
			(start 0.299974 0.150114)
			(end 0.299974 -0.150114)
			(stroke
				(width 0.1)
				(type default)
			)
			(layer "B.Fab")
		)
		(fp_line
			(start -0.299974 0.150114)
			(end 0.299974 0.150114)
			(stroke
				(width 0.1)
				(type default)
			)
			(layer "B.Fab")
		)
		(pad "1" smd rect
			(at 0.2667 0 270)
			(size 0.3048 0.381)
			(layers "B.Cu" "B.Mask" "B.Paste")
			(net "P1V8_CPU0_RT2_1A")
		)
		(pad "2" smd rect
			(at -0.2667 0 270)
			(size 0.3048 0.381)
			(layers "B.Cu" "B.Mask" "B.Paste")
			(net "GND")
		)
	)
)
